FILE_TYPE = CONNECTIVITY;
{Allegro Design Entry HDL 16.6-p007 (v16-6-112F) 10/10/2012}
"PAGE_NUMBER" = 186;
0"NC";
1"P3E_OCP_CPU0_PE3_C_TXP<15:8>";
2"P3E_OCP_CPU0_PE3_C_TXN<15:8>";
3"P3E_CPU0_PE3_OCP_RXN<15:8>";
4"P3E_CPU0_PE3_OCP_RXP<15:8>";
5"GND\g";
6"GND\g";
7"GND\g";
8"P3V3\g";
9"GND\g";
10"P3V3\g";
11"P3V3\g";
12"GND\g";
13"P3V3_STBY\g";
14"P3V3_STBY\g";
15"P5V_STBY\g";
16"P12V_STBY\g";
17"P12V_STBY\g";
18"P3V3_STBY\g";
19"GND\g";
20"P5V_STBY\g";
21"P3V3_STBY\g";
22"GND\g";
23"P3E_CPU0_PE3_OCP_RXP<9>";
24"P3E_OCP_CPU0_PE3_C_TXP<9>";
25"P3E_OCP_CPU0_PE3_C_TXP<10>";
26"P3E_OCP_CPU0_PE3_C_TXP<11>";
27"P3E_OCP_CPU0_PE3_C_TXP<8>";
28"P3E_OCP_CPU0_PE3_C_TXN<8>";
29"P3E_CPU0_PE3_OCP_RXP<8>";
30"P3E_CPU0_PE3_OCP_RXN<8>";
31"P3E_CPU0_PE3_OCP_RXN<9>";
32"FM_OCP_MEZZA_PRES_N";
33"CLK_100M_MEZZ1_DP";
34"CLK_100M_MEZZ1_DN";
35"P3E_OCP_CPU0_PE3_C_TXP<15>";
36"P3E_OCP_CPU0_PE3_C_TXN<15>";
37"P3E_OCP_CPU0_PE3_C_TXP<14>";
38"P3E_OCP_CPU0_PE3_C_TXN<14>";
39"P3E_OCP_CPU0_PE3_C_TXP<13>";
40"P3E_OCP_CPU0_PE3_C_TXN<13>";
41"P3E_OCP_CPU0_PE3_C_TXN<11>";
42"FM_MEZZA_PRSNT1_N";
43"RMII_BMC_OCP_CRSDV_R";
44"CLK_100M_MEZZ2_DP";
45"RMII_BMC_OCP_RXD1_R";
46"RMII_BMC_OCP_RXD0_R";
47"RMII_BMC_OCP_RXD1";
48"RMII_BMC_OCP_RXD0";
49"RST_PCIE_CPU_DEV0_N";
50"RST_PCIE_CPU_DEV0_R_N";
51"RMII_BMC_OCP_TXEN";
52"CLK_50M_CKMNG_OCP";
53"P3E_CPU0_PE3_OCP_RXP<14>";
54"P3E_CPU0_PE3_OCP_RXN<14>";
55"P3E_CPU0_PE3_OCP_RXP<13>";
56"P3E_CPU0_PE3_OCP_RXN<13>";
57"RMII_BMC_OCP_RXER";
58"SMB_OCP_LAN_STBY_LVC3_SCL";
59"SMB_OCP_LAN_STBY_LVC3_SDA";
60"FM_PE_OCP_WAKE_N";
61"SMB_OCP_FRU_STBY_LVC3_SDA";
62"SMB_OCP_FRU_STBY_LVC3_SCL";
63"IRQ_MEZZ_LAN_ALERT_N";
64"RMII_BMC_OCP_CRSDV";
65"P3E_CPU0_PE3_OCP_RXP<10>";
66"P3E_CPU0_PE3_OCP_RXN<11>";
67"P3E_CPU0_PE3_OCP_RXP<11>";
68"P3E_CPU0_PE3_OCP_RXN<12>";
69"P3E_CPU0_PE3_OCP_RXP<12>";
70"CLK_100M_MEZZ2_DN";
71"P3E_CPU0_PE3_OCP_RXP<15>";
72"P3E_CPU0_PE3_OCP_RXN<15>";
73"P3E_CPU0_PE3_OCP_RXN<10>";
74"P3E_OCP_CPU0_PE3_C_TXN<12>";
75"RMII_BMC_OCP_RXER_R";
76"P3E_OCP_CPU0_PE3_C_TXN<9>";
77"P3E_OCP_CPU0_PE3_C_TXN<10>";
78"P3E_OCP_CPU0_PE3_C_TXP<12>";
79"RMII_BMC_OCP_TXD1";
80"RMII_BMC_OCP_TXD0";
%"CAP_A"
"1","(10850,4675)","0","dev_discrete","I10";
;
LOCATION"C1M24"
TOLERANCE"10%"
PACK_TYPE"0402V"
VOLTAGE"16V"
PART_NUMBER"A36096-030"
MATERIAL"X7R"
VALUE"0.1UF"
ROOM"IO_SLOT"
SEC"1"
SEC_TYPE"0402V"
CDS_SEC"1"
CDS_LIB"dev_discrete"
CDS_LOCATION"C1M24";
"B"
$PN"2"22;
"A"
$PN"1"11;
%"GND"
"1","(11650,3550)","0","mstr_symbols","I14";
;
VOLTAGE"0"
HDL_POWER"GND"
BODY_TYPE"PLUMBING"
SIZE"1B"
CDS_LIB"mstr_symbols";
"A\NAC"5;
%"GND"
"1","(7525,700)","0","mstr_symbols","I192";
;
VOLTAGE"0"
HDL_POWER"GND"
BODY_TYPE"PLUMBING"
SIZE"1B"
CDS_LIB"mstr_symbols";
"A\NAC"6;
%"GND"
"1","(8975,725)","0","mstr_symbols","I193";
;
VOLTAGE"0"
HDL_POWER"GND"
BODY_TYPE"PLUMBING"
CDS_LIB"mstr_symbols"
SIZE"1B";
"A\NAC"7;
%"P3V3"
"1","(7000,3500)","0","mstr_symbols","I195";
;
VOLTAGE"+3.3"
HDL_POWER"P3V3"
BODY_TYPE"PLUMBING"
SIZE"1B"
CDS_LIB"mstr_symbols";
"G\NAC"8;
%"RES"
"1","(6000,3050)","0","mstr_discrete","I220";
;
CDS_SEC"1"
LOCATION"R1M14"
PART_NUMBER"G21796-004"
VALUE"200.0"
WATTAGE"1/16W"
MATERIAL"CHIP"
TOLERANCE"1%"
PACK_TYPE"0402"
ROOM"IO_SLOT"
CDS_LOCATION"R1M14"
SEC"1"
CDS_LIB"mstr_discrete"
SEC_TYPE"0402";
"B"
$PN"2"50;
"A"
$PN"1"49;
%"GND"
"1","(6300,3450)","0","mstr_symbols","I223";
;
CDS_LIB"mstr_symbols"
SIZE"1B"
BODY_TYPE"PLUMBING"
HDL_POWER"GND"
VOLTAGE"0";
"A\NAC"9;
%"P3V3"
"1","(8850,4050)","0","mstr_symbols","I247";
;
VOLTAGE"+3.3"
HDL_POWER"P3V3"
BODY_TYPE"PLUMBING"
SIZE"1B"
CDS_LIB"mstr_symbols";
"G\NAC"10;
%"P3V3"
"1","(10450,4950)","0","mstr_symbols","I268";
;
VOLTAGE"+3.3"
HDL_POWER"P3V3"
BODY_TYPE"PLUMBING"
CDS_LIB"mstr_symbols"
SIZE"1B";
"G\NAC"11;
%"GND"
"1","(11650,4275)","0","mstr_symbols","I269";
;
VOLTAGE"0"
HDL_POWER"GND"
SIZE"1B"
BODY_TYPE"PLUMBING"
CDS_LIB"mstr_symbols";
"A\NAC"12;
%"CAP_A"
"1","(11650,4675)","0","dev_discrete","I270";
;
CDS_SEC"1"
VALUE"0.1UF"
TOLERANCE"10%"
VOLTAGE"16V"
LOCATION"C1M20"
PACK_TYPE"0402V"
PART_NUMBER"A36096-030"
MATERIAL"X7R"
ROOM"IO_SLOT"
CDS_LOCATION"C1M20"
CDS_LIB"dev_discrete"
SEC"1"
SEC_TYPE"0402V";
"B"
$PN"2"12;
"A"
$PN"1"18;
%"P3V3_STBY"
"1","(7375,4025)","0","mstr_symbols","I274";
;
VOLTAGE"3.3V"
HDL_POWER"P3V3_STBY"
BODY_TYPE"PLUMBING"
SIZE"1B"
CDS_LIB"mstr_symbols";
"G\NAC"13;
%"P3V3_STBY"
"1","(8725,4200)","0","mstr_symbols","I275";
;
VOLTAGE"3.3V"
HDL_POWER"P3V3_STBY"
BODY_TYPE"PLUMBING"
CDS_LIB"mstr_symbols"
SIZE"1B";
"G\NAC"14;
%"P5V_STBY"
"1","(7650,4050)","0","mstr_symbols","I276";
;
VOLTAGE"5.0V"
HDL_POWER"P5V_STBY"
SIZE"1B"
BODY_TYPE"PLUMBING"
CDS_LIB"mstr_symbols";
"G\NAC"15;
%"P12V_STBY"
"1","(9200,4225)","0","mstr_symbols","I278";
;
SIZE"1B"
CDS_LIB"mstr_symbols"
BODY_TYPE"PLUMBING"
HDL_POWER"P12V_STBY"
VOLTAGE"12.0V";
"G\NAC"16;
%"P12V_STBY"
"1","(10450,4225)","0","mstr_symbols","I279";
;
VOLTAGE"12.0V"
HDL_POWER"P12V_STBY"
BODY_TYPE"PLUMBING"
CDS_LIB"mstr_symbols"
SIZE"1B";
"G\NAC"17;
%"P3V3_STBY"
"1","(11250,4950)","0","mstr_symbols","I296";
;
VOLTAGE"3.3V"
HDL_POWER"P3V3_STBY"
BODY_TYPE"PLUMBING"
CDS_LIB"mstr_symbols"
SIZE"1B";
"G\NAC"18;
%"TAP"
"1","(6250,1750)","2","mstr_standard","I297";
;
HDL_TAP"TRUE"
BODY_TYPE"PLUMBING"
CDS_LIB"mstr_standard";
"B \NAC \NWC"3;
"S \NAC"
BN"12"68;
%"TAP"
"1","(6250,1550)","2","mstr_standard","I298";
;
HDL_TAP"TRUE"
BODY_TYPE"PLUMBING"
CDS_LIB"mstr_standard";
"B \NAC \NWC"3;
"S \NAC"
BN"11"66;
%"TAP"
"1","(6250,1350)","2","mstr_standard","I299";
;
HDL_TAP"TRUE"
BODY_TYPE"PLUMBING"
CDS_LIB"mstr_standard";
"B \NAC \NWC"3;
"S \NAC"
BN"10"73;
%"CAP"
"1","(10450,3975)","0","mstr_discrete","I3";
;
CDS_SEC"1"
LOCATION"C1M27"
VALUE"10UF"
TOLERANCE"10%"
VOLTAGE"16V"
MATERIAL"X6S"
PACK_TYPE"0805"
PART_NUMBER"C95333-007"
ROOM"IO_SLOT"
CDS_LOCATION"C1M27"
SEC"1"
CDS_LIB"mstr_discrete"
SEC_TYPE"0805";
"A"
$PN"1"17;
"B"
$PN"2"5;
%"TAP"
"1","(6425,1000)","2","mstr_standard","I300";
;
HDL_TAP"TRUE"
BODY_TYPE"PLUMBING"
CDS_LIB"mstr_standard";
"B \NAC \NWC"4;
"S \NAC"
BN"8"29;
%"TAP"
"1","(6425,2200)","2","mstr_standard","I301";
;
HDL_TAP"TRUE"
BODY_TYPE"PLUMBING"
CDS_LIB"mstr_standard";
"B \NAC \NWC"4;
"S \NAC"
BN"14"53;
%"TAP"
"1","(6425,2400)","2","mstr_standard","I302";
;
HDL_TAP"TRUE"
BODY_TYPE"PLUMBING"
CDS_LIB"mstr_standard";
"B \NAC \NWC"4;
"S \NAC"
BN"15"71;
%"TAP"
"1","(6250,2350)","2","mstr_standard","I303";
;
HDL_TAP"TRUE"
BODY_TYPE"PLUMBING"
CDS_LIB"mstr_standard";
"B \NAC \NWC"3;
"S \NAC"
BN"15"72;
%"TAP"
"1","(6425,2000)","2","mstr_standard","I304";
;
HDL_TAP"TRUE"
BODY_TYPE"PLUMBING"
CDS_LIB"mstr_standard";
"B \NAC \NWC"4;
"S \NAC"
BN"13"55;
%"TAP"
"1","(6425,1800)","2","mstr_standard","I305";
;
HDL_TAP"TRUE"
BODY_TYPE"PLUMBING"
CDS_LIB"mstr_standard";
"B \NAC \NWC"4;
"S \NAC"
BN"12"69;
%"TAP"
"1","(6250,2150)","2","mstr_standard","I306";
;
HDL_TAP"TRUE"
BODY_TYPE"PLUMBING"
CDS_LIB"mstr_standard";
"B \NAC \NWC"3;
"S \NAC"
BN"14"54;
%"TAP"
"1","(6250,1950)","2","mstr_standard","I307";
;
HDL_TAP"TRUE"
BODY_TYPE"PLUMBING"
CDS_LIB"mstr_standard";
"B \NAC \NWC"3;
"S \NAC"
BN"13"56;
%"TAP"
"1","(6425,1600)","2","mstr_standard","I308";
;
HDL_TAP"TRUE"
BODY_TYPE"PLUMBING"
CDS_LIB"mstr_standard";
"B \NAC \NWC"4;
"S \NAC"
BN"11"67;
%"TAP"
"1","(6425,1400)","2","mstr_standard","I309";
;
HDL_TAP"TRUE"
BODY_TYPE"PLUMBING"
CDS_LIB"mstr_standard";
"B \NAC \NWC"4;
"S \NAC"
BN"10"65;
%"TAP"
"1","(6425,1200)","2","mstr_standard","I310";
;
HDL_TAP"TRUE"
BODY_TYPE"PLUMBING"
CDS_LIB"mstr_standard";
"B \NAC \NWC"4;
"S \NAC"
BN"9"23;
%"TAP"
"1","(6250,1150)","2","mstr_standard","I311";
;
HDL_TAP"TRUE"
BODY_TYPE"PLUMBING"
CDS_LIB"mstr_standard";
"B \NAC \NWC"3;
"S \NAC"
BN"9"31;
%"TAP"
"1","(6250,950)","2","mstr_standard","I312";
;
HDL_TAP"TRUE"
BODY_TYPE"PLUMBING"
CDS_LIB"mstr_standard";
"B \NAC \NWC"3;
"S \NAC"
BN"8"30;
%"TAP"
"1","(10250,1850)","0","mstr_standard","I315";
;
HDL_TAP"TRUE"
BODY_TYPE"PLUMBING"
CDS_LIB"mstr_standard";
"B \NAC \NWC"2;
"S \NAC"
BN"12"74;
%"TAP"
"1","(10050,2100)","0","mstr_standard","I316";
;
HDL_TAP"TRUE"
BODY_TYPE"PLUMBING"
CDS_LIB"mstr_standard";
"B \NAC \NWC"1;
"S \NAC"
BN"13"39;
%"TAP"
"1","(10050,2300)","0","mstr_standard","I317";
;
HDL_TAP"TRUE"
BODY_TYPE"PLUMBING"
CDS_LIB"mstr_standard";
"B \NAC \NWC"1;
"S \NAC"
BN"14"37;
%"TAP"
"1","(10050,2500)","0","mstr_standard","I318";
;
HDL_TAP"TRUE"
BODY_TYPE"PLUMBING"
CDS_LIB"mstr_standard";
"B \NAC \NWC"1;
"S \NAC"
BN"15"35;
%"TAP"
"1","(10250,2450)","0","mstr_standard","I321";
;
HDL_TAP"TRUE"
BODY_TYPE"PLUMBING"
CDS_LIB"mstr_standard";
"B \NAC \NWC"2;
"S \NAC"
BN"15"36;
%"TAP"
"1","(10250,2250)","0","mstr_standard","I322";
;
HDL_TAP"TRUE"
BODY_TYPE"PLUMBING"
CDS_LIB"mstr_standard";
"B \NAC \NWC"2;
"S \NAC"
BN"14"38;
%"TAP"
"1","(10250,2050)","0","mstr_standard","I323";
;
HDL_TAP"TRUE"
BODY_TYPE"PLUMBING"
CDS_LIB"mstr_standard";
"B \NAC \NWC"2;
"S \NAC"
BN"13"40;
%"TAP"
"1","(10250,1650)","0","mstr_standard","I324";
;
HDL_TAP"TRUE"
BODY_TYPE"PLUMBING"
CDS_LIB"mstr_standard";
"B \NAC \NWC"2;
"S \NAC"
BN"11"41;
%"TAP"
"1","(10050,1700)","0","mstr_standard","I325";
;
HDL_TAP"TRUE"
BODY_TYPE"PLUMBING"
CDS_LIB"mstr_standard";
"B \NAC \NWC"1;
"S \NAC"
BN"11"26;
%"TAP"
"1","(10050,1900)","0","mstr_standard","I326";
;
HDL_TAP"TRUE"
BODY_TYPE"PLUMBING"
CDS_LIB"mstr_standard";
"B \NAC \NWC"1;
"S \NAC"
BN"12"78;
%"TAP"
"1","(10250,1450)","0","mstr_standard","I327";
;
HDL_TAP"TRUE"
BODY_TYPE"PLUMBING"
CDS_LIB"mstr_standard";
"B \NAC \NWC"2;
"S \NAC"
BN"10"77;
%"TAP"
"1","(10250,1250)","0","mstr_standard","I328";
;
HDL_TAP"TRUE"
BODY_TYPE"PLUMBING"
CDS_LIB"mstr_standard";
"B \NAC \NWC"2;
"S \NAC"
BN"9"76;
%"TAP"
"1","(10050,1300)","0","mstr_standard","I329";
;
HDL_TAP"TRUE"
BODY_TYPE"PLUMBING"
CDS_LIB"mstr_standard";
"B \NAC \NWC"1;
"S \NAC"
BN"9"24;
%"TAP"
"1","(10050,1500)","0","mstr_standard","I330";
;
HDL_TAP"TRUE"
BODY_TYPE"PLUMBING"
CDS_LIB"mstr_standard";
"B \NAC \NWC"1;
"S \NAC"
BN"10"25;
%"TAP"
"1","(10250,1050)","0","mstr_standard","I331";
;
HDL_TAP"TRUE"
BODY_TYPE"PLUMBING"
CDS_LIB"mstr_standard";
"B \NAC \NWC"2;
"S \NAC"
BN"8"28;
%"TAP"
"1","(10050,1100)","0","mstr_standard","I332";
;
HDL_TAP"TRUE"
BODY_TYPE"PLUMBING"
CDS_LIB"mstr_standard";
"B \NAC \NWC"1;
"S \NAC"
BN"8"27;
%"CAP_A"
"1","(10450,4700)","0","dev_discrete","I334";
;
VALUE"1.0UF"
TOLERANCE"10%"
VOLTAGE"6.3V"
MATERIAL"X6S"
LOCATION"C1M21"
PART_NUMBER"D97712-004"
PACK_TYPE"0402V"
ROOM"IO_SLOT"
SEC"1"
SEC_TYPE"0402V"
CDS_SEC"1"
CDS_LIB"dev_discrete"
CDS_LOCATION"C1M21";
"B"
$PN"2"22;
"A"
$PN"1"11;
%"CAP_A"
"1","(11250,4700)","0","dev_discrete","I335";
;
LOCATION"C1M25"
VALUE"1.0UF"
TOLERANCE"10%"
VOLTAGE"6.3V"
MATERIAL"X6S"
PART_NUMBER"D97712-004"
PACK_TYPE"0402V"
ROOM"IO_SLOT"
SEC_TYPE"0402V"
SEC"1"
CDS_LOCATION"C1M25"
CDS_LIB"dev_discrete"
CDS_SEC"1";
"B"
$PN"2"12;
"A"
$PN"1"18;
%"SCONN120_A28699018"
"1","(8250,2350)","0","mstr_sconn","I336";
;
CDS_SEC"1"
MATERIAL"SCONN"
PART_NUMBER"A28699-018"
LOCATION"J9B3"
GROUP"NO_KR"
CDS_LIB"mstr_sconn"
SEC_TYPE"SM"
SEC"1"
CDS_LOCATION"J9B3"
ROOM"IO_SLOT"
PACK_TYPE"SM";
"IO1"
$PN"1"42;
"IO3"
$PN"3"15;
"IO120"
$PN"120"32;
"IO118"
$PN"118"7;
"IO114"
$PN"114"28;
"IO116"
$PN"116"7;
"IO112"
$PN"112"27;
"IO110"
$PN"110"7;
"IO108"
$PN"108"7;
"IO106"
$PN"106"76;
"IO104"
$PN"104"24;
"IO102"
$PN"102"7;
"IO100"
$PN"100"7;
"IO98"
$PN"98"77;
"IO94"
$PN"94"7;
"IO96"
$PN"96"25;
"IO88"
$PN"88"26;
"IO90"
$PN"90"41;
"IO92"
$PN"92"7;
"IO86"
$PN"86"7;
"IO84"
$PN"84"7;
"IO82"
$PN"82"74;
"IO78"
$PN"78"7;
"IO80"
$PN"80"78;
"IO74"
$PN"74"40;
"IO76"
$PN"76"7;
"IO72"
$PN"72"39;
"IO70"
$PN"70"7;
"IO68"
$PN"68"7;
"IO66"
$PN"66"38;
"IO64"
$PN"64"37;
"IO62"
$PN"62"7;
"IO58"
$PN"58"36;
"IO60"
$PN"60"7;
"IO52"
$PN"52"7;
"IO54"
$PN"54"7;
"IO56"
$PN"56"35;
"IO50"
$PN"50"34;
"IO48"
$PN"48"33;
"IO46"
$PN"46"7;
"IO44"
$PN"44"7;
"IO42"
$PN"42"79;
"IO38"
$PN"38"7;
"IO40"
$PN"40"80;
"IO36"
$PN"36"75;
"IO32"
$PN"32"61;
"IO34"
$PN"34"60;
"IO30"
$PN"30"62;
"IO28"
$PN"28"63;
"IO26"
$PN"26"7;
"IO24"
$PN"24"10;
"IO22"
$PN"22"10;
"IO16"
$PN"16"7;
"IO18"
$PN"18"10;
"IO20"
$PN"20"10;
"IO14"
$PN"14"7;
"IO12"
$PN"12"14;
"IO8"
$PN"8"7;
"IO10"
$PN"10"7;
"IO6"
$PN"6"16;
"IO2"
$PN"2"16;
"IO4"
$PN"4"16;
"IO119"
$PN"119"6;
"IO117"
$PN"117"30;
"IO113"
$PN"113"6;
"IO115"
$PN"115"29;
"IO111"
$PN"111"6;
"IO109"
$PN"109"31;
"IO107"
$PN"107"23;
"IO105"
$PN"105"6;
"IO103"
$PN"103"6;
"IO101"
$PN"101"73;
"IO97"
$PN"97"6;
"IO99"
$PN"99"65;
"IO93"
$PN"93"66;
"IO95"
$PN"95"6;
"IO89"
$PN"89"6;
"IO87"
$PN"87"6;
"IO91"
$PN"91"67;
"IO85"
$PN"85"68;
"IO83"
$PN"83"69;
"IO81"
$PN"81"6;
"IO77"
$PN"77"56;
"IO79"
$PN"79"6;
"IO73"
$PN"73"6;
"IO75"
$PN"75"55;
"IO71"
$PN"71"6;
"IO69"
$PN"69"54;
"IO67"
$PN"67"53;
"IO65"
$PN"65"6;
"IO63"
$PN"63"6;
"IO61"
$PN"61"72;
"IO57"
$PN"57"6;
"IO59"
$PN"59"71;
"IO51"
$PN"51"44;
"IO53"
$PN"53"70;
"IO55"
$PN"55"6;
"IO49"
$PN"49"6;
"IO47"
$PN"47"6;
"IO45"
$PN"45"45;
"IO43"
$PN"43"46;
"IO41"
$PN"41"6;
"IO37"
$PN"37"59;
"IO39"
$PN"39"6;
"IO35"
$PN"35"58;
"IO31"
$PN"31"51;
"IO33"
$PN"33"50;
"IO29"
$PN"29"52;
"IO27"
$PN"27"43;
"IO25"
$PN"25"8;
"IO23"
$PN"23"8;
"IO21"
$PN"21"8;
"IO15"
$PN"15"6;
"IO17"
$PN"17"6;
"IO19"
$PN"19"8;
"IO13"
$PN"13"13;
"IO11"
$PN"11"6;
"IO9"
$PN"9"6;
"IO7"
$PN"7"15;
"IO5"
$PN"5"15;
%"RES"
"1","(6700,2750)","0","mstr_discrete","I337";
;
CDS_SEC"1"
PART_NUMBER"G21497-005"
TOLERANCE"5%"
LOCATION"R1M16"
VALUE"0.0"
WATTAGE"1/16W"
MATERIAL"CHIP"
PACK_TYPE"0402"
ROOM"IO_SLOT"
CDS_LOCATION"R1M16"
SEC"1"
SEC_TYPE"0402"
CDS_LIB"mstr_discrete";
"B"
$PN"2"45;
"A"
$PN"1"47;
%"RES"
"1","(6375,2800)","0","mstr_discrete","I338";
;
CDS_SEC"1"
TOLERANCE"5%"
PART_NUMBER"G21497-005"
VALUE"0.0"
LOCATION"R1M17"
WATTAGE"1/16W"
MATERIAL"CHIP"
PACK_TYPE"0402"
ROOM"IO_SLOT"
CDS_LOCATION"R1M17"
SEC"1"
CDS_LIB"mstr_discrete"
SEC_TYPE"0402";
"B"
$PN"2"46;
"A"
$PN"1"48;
%"RES"
"1","(6375,3200)","0","mstr_discrete","I339";
;
CDS_SEC"1"
PART_NUMBER"G21497-005"
VALUE"0.0"
TOLERANCE"5%"
WATTAGE"1/16W"
MATERIAL"CHIP"
PACK_TYPE"0402"
LOCATION"R1M15"
ROOM"IO_SLOT"
CDS_LOCATION"R1M15"
SEC"1"
CDS_LIB"mstr_discrete"
SEC_TYPE"0402";
"B"
$PN"2"43;
"A"
$PN"1"64;
%"RES"
"1","(10250,3000)","0","mstr_discrete","I340";
;
CDS_SEC"1"
LOCATION"R1M18"
PART_NUMBER"G21497-005"
TOLERANCE"5%"
VALUE"0.0"
PACK_TYPE"0402"
MATERIAL"CHIP"
WATTAGE"1/16W"
ROOM"IO_SLOT"
CDS_LOCATION"R1M18"
SEC"1"
CDS_LIB"mstr_discrete"
SEC_TYPE"0402";
"B"
$PN"2"57;
"A"
$PN"1"75;
%"CAP_A"
"1","(10050,3950)","0","dev_discrete","I345";
;
CDS_SEC"1"
CDS_LOCATION"C9B10"
VALUE"0.1UF"
VOLTAGE"16V"
TOLERANCE"10%"
PACK_TYPE"0402V"
PART_NUMBER"A36096-030"
MATERIAL"X7R"
LOCATION"C9B10"
ROOM"IO_SLOT"
SEC_TYPE"0402V"
SEC"1"
CDS_LIB"dev_discrete";
"B"
$PN"2"19;
"A"
$PN"1"20;
%"GND"
"1","(10050,3600)","0","mstr_symbols","I346";
;
VOLTAGE"0"
HDL_POWER"GND"
CDS_LIB"mstr_symbols"
BODY_TYPE"PLUMBING"
SIZE"1B";
"A\NAC"19;
%"P5V_STBY"
"1","(9650,4300)","0","mstr_symbols","I348";
;
VOLTAGE"5.0V"
HDL_POWER"P5V_STBY"
CDS_LIB"mstr_symbols"
BODY_TYPE"PLUMBING"
SIZE"1B";
"G\NAC"20;
%"P3V3_STBY"
"1","(6300,4250)","0","mstr_symbols","I350";
;
SIZE"1B"
BODY_TYPE"PLUMBING"
HDL_POWER"P3V3_STBY"
VOLTAGE"3.3V"
CDS_LIB"mstr_symbols";
"G\NAC"21;
%"RES"
"2","(6300,4000)","0","mstr_discrete","I356";
;
CDS_SEC"1"
CDS_LOCATION"R9W1"
PACK_TYPE"0402"
MATERIAL"CHIP"
WATTAGE"1/16W"
TOLERANCE"1%"
VALUE"10.0K"
PART_NUMBER"G21796-016"
LOCATION"R9W1"
CDS_LIB"mstr_discrete"
ROOM"CPU0"
BOM_COST"PROC_SIDEBAND"
SEC"1"
SEC_TYPE"0402";
"A"
$PN"1"21;
"B"
$PN"2"42;
%"SC1U10V2KX-4-GP"
"1","(9650,3925)","0","w_hdl","I357";
;
CDS_SEC"1"
CDS_LOCATION"C9B9"
RATED"10V"
TOLERANCE"10%"
ATTRIBUTE"1UF"
PACK_SIZE"0402"
LOCATION"C9B9"
VALUE"SC1U10V2KX-4-GP"
CDS_LMAN_SYM_OUTLINE"-50,25,50,-25"
CDS_LIB"w_hdl"
PART_NUMBER"78.10523.8FL"
SEC_TYPE"SMD-BCG6"
SEC"1"
PACK_TYPE"SMD-BCG6";
"2"
$PN"2"19;
"1"
$PN"1"20;
%"887R2F-L-GP"
"1","(6300,3675)","0","w_hdl","I358";
;
CDS_SEC"1"
CDS_LOCATION"R9B7"
PACK_SIZE"0402"
LOCATION"R9B7"
RATED"1/16W"
TOLERANCE"1%"
VALUE"887R2F-L-GP"
ATTRIBUTE"887OHM"
PACK_TYPE"SMD-RG"
SEC"1"
SEC_TYPE"SMD-RG"
PART_NUMBER"64.88705.6DL"
CDS_LIB"w_hdl"
CDS_LMAN_SYM_OUTLINE"-50,75,50,-75";
"2"
$PN"2"9;
"1"
$PN"1"42;
%"CAP"
"1","(10850,3950)","0","mstr_discrete","I6";
;
CDS_SEC"1"
VOLTAGE"16V"
TOLERANCE"10%"
PART_NUMBER"C95333-007"
PACK_TYPE"0805"
MATERIAL"X6S"
LOCATION"C1M26"
VALUE"10UF"
ROOM"IO_SLOT"
CDS_LOCATION"C1M26"
SEC"1"
CDS_LIB"mstr_discrete"
SEC_TYPE"0805";
"A"
$PN"1"17;
"B"
$PN"2"5;
%"CAP_A"
"1","(11225,3950)","0","dev_discrete","I7";
;
PACK_TYPE"0402V"
VOLTAGE"16V"
VALUE"0.1UF"
LOCATION"C1M23"
MATERIAL"X7R"
PART_NUMBER"A36096-030"
TOLERANCE"10%"
ROOM"IO_SLOT"
SEC"1"
SEC_TYPE"0402V"
CDS_SEC"1"
CDS_LIB"dev_discrete"
CDS_LOCATION"C1M23";
"B"
$PN"2"5;
"A"
$PN"1"17;
%"CAP_A"
"1","(11650,3950)","0","dev_discrete","I8";
;
PACK_TYPE"0402V"
PART_NUMBER"A36096-030"
LOCATION"C1M22"
TOLERANCE"10%"
VOLTAGE"16V"
MATERIAL"X7R"
VALUE"0.1UF"
ROOM"IO_SLOT"
SEC"1"
SEC_TYPE"0402V"
CDS_SEC"1"
CDS_LIB"dev_discrete"
CDS_LOCATION"C1M22";
"B"
$PN"2"5;
"A"
$PN"1"17;
%"GND"
"1","(10850,4275)","0","mstr_symbols","I9";
;
VOLTAGE"0"
HDL_POWER"GND"
BODY_TYPE"PLUMBING"
CDS_LIB"mstr_symbols"
SIZE"1B";
"A\NAC"22;
END.
